# TIMECARD (Time Appliance Project (Time Card)) — schematic netlist excerpt (pin names and nets, part order shuffled) for the footprints in the layout excerpt that follows; sources: Cadence DE-HDL packaged netlist, KiCad conversion of R4006-B0001-02_R01.brd

R207  RESISTOR  0OHM -  pkg SMC_0402R_H016  page 10 : \1\ = CCLK_0 ; \2\ = FPGA_FLASH_CLK
C64  CAPACITOR  10UF 25V 20%  pkg SMC_0805R_H057  page 21 : \1\ = XP5R0V_MAC_USB ; \2\ = SG

(kicad_pcb
	(version 20260206)
	(generator "pcbnew")
	(generator_version "10.0")
	(general
		(thickness 1.6)
		(legacy_teardrops no)
	)
	(paper "A4")
	(title_block
		(title "timecard-production-celestica-r4006 — R4006-B0001-02_R01.brd")
		(comment 1 "Time Appliance Project (Time Card) / footprints 779-780 of 1113")
	)
	(layers
		(0 "F.Cu" signal "TOP")
		(4 "In1.Cu" signal "L02_GND1")
		(6 "In2.Cu" signal "L03_SIG1")
		(8 "In3.Cu" signal "L04_GND2")
		(10 "In4.Cu" signal "L05_VCC1")
		(12 "In5.Cu" signal "L06_VCC2")
		(14 "In6.Cu" signal "L07_GND3")
		(16 "In7.Cu" signal "L08_SIG2")
		(18 "In8.Cu" signal "L09_GND4")
		(2 "B.Cu" signal "BOTTOM")
		(9 "F.Adhes" user "F.Adhesive")
		(11 "B.Adhes" user "B.Adhesive")
		(13 "F.Paste" user "Package Geometry/Pastemask Top")
		(15 "B.Paste" user "Package Geometry/Pastemask Bottom")
		(5 "F.SilkS" user "Ref Des/Silkscreen Top")
		(7 "B.SilkS" user "Ref Des/Silkscreen Bottom")
		(1 "F.Mask" user "Board Geometry/Soldermask Top")
		(3 "B.Mask" user "Board Geometry/Soldermask Bottom")
		(17 "Dwgs.User" user "User.Drawings")
		(19 "Cmts.User" user "User.Comments")
		(21 "Eco1.User" user "User.Eco1")
		(23 "Eco2.User" user "User.Eco2")
		(25 "Edge.Cuts" user "Board Geometry/Outline")
		(27 "Margin" user)
		(31 "F.CrtYd" user "Package Geometry/Place Bound Top")
		(29 "B.CrtYd" user "Package Geometry/Place Bound Bottom")
		(35 "F.Fab" user "Ref Des/Assembly Top")
		(33 "B.Fab" user "Ref Des/Assembly Bottom")
	)
	(footprint ""
		(layer "B.Cu")
		(at 110.49 -61.976 -90)
		(property "Reference" "R207"
			(at -3.81 0.03937 270)
			(unlocked yes)
			(layer "B.SilkS")
			(effects
				(font
					(size 0.7874 0.5842)
					(thickness 0.1524)
				)
				(justify mirror)
			)
		)
		(property "Value" "VAL*"
			(at -0.02032 2.13233 270)
			(unlocked yes)
			(layer "B.Fab")
			(hide yes)
			(effects
				(font
					(size 0.7874 0.5842)
					(thickness 0.1524)
				)
				(justify mirror)
			)
		)
		(property "Device Type" "RESISTOR-G155-149R9-01,49.9OHMA"
			(at -0.008382 1.210564 270)
			(unlocked yes)
			(layer "B.Fab")
			(hide yes)
			(effects
				(font
					(size 0.7874 0.5842)
					(thickness 0.1524)
				)
				(justify mirror)
			)
		)
		(property "User Part Number" "PARTNUM*"
			(at -0.02032 4.024884 270)
			(unlocked yes)
			(layer "Cmts.User")
			(hide yes)
			(effects
				(font
					(size 0.7874 0.5842)
					(thickness 0.1524)
				)
				(justify mirror)
			)
		)
		(property "Tolerance" "TOL*"
			(at -0.044704 3.05435 270)
			(unlocked yes)
			(layer "Cmts.User")
			(hide yes)
			(effects
				(font
					(size 0.7874 0.5842)
					(thickness 0.1524)
				)
				(justify mirror)
			)
		)
		(duplicate_pad_numbers_are_jumpers no)
		(fp_line
			(start -1.143 0.5588)
			(end -1.143 -0.5588)
			(stroke
				(width 0.1)
				(type default)
			)
			(layer "B.SilkS")
		)
		(fp_line
			(start 1.143 0.5588)
			(end -1.143 0.5588)
			(stroke
				(width 0.1)
				(type default)
			)
			(layer "B.SilkS")
		)
		(fp_line
			(start -1.143 -0.5588)
			(end 1.143 -0.5588)
			(stroke
				(width 0.1)
				(type default)
			)
			(layer "B.SilkS")
		)
		(fp_line
			(start 1.143 -0.5588)
			(end 1.143 0.5588)
			(stroke
				(width 0.1)
				(type default)
			)
			(layer "B.SilkS")
		)
		(fp_rect
			(start -1.143 0.5588)
			(end 1.143 -0.5588)
			(stroke
				(width 0)
				(type default)
			)
			(fill no)
			(layer "B.CrtYd")
		)
		(fp_line
			(start -0.508 0.3048)
			(end -0.508 -0.3048)
			(stroke
				(width 0.1)
				(type default)
			)
			(layer "B.Fab")
		)
		(fp_line
			(start 0.508 0.3048)
			(end -0.508 0.3048)
			(stroke
				(width 0.1)
				(type default)
			)
			(layer "B.Fab")
		)
		(fp_line
			(start -0.508 -0.3048)
			(end 0.508 -0.3048)
			(stroke
				(width 0.1)
				(type default)
			)
			(layer "B.Fab")
		)
		(fp_line
			(start 0.508 -0.3048)
			(end 0.508 0.3048)
			(stroke
				(width 0.1)
				(type default)
			)
			(layer "B.Fab")
		)
		(pad "1" smd rect
			(at 0.5334 0 90)
			(size 0.7112 0.6096)
			(layers "B.Cu" "B.Mask" "B.Paste")
			(net "CCLK_0")
		)
		(pad "2" smd rect
			(at -0.5334 0 90)
			(size 0.7112 0.6096)
			(layers "B.Cu" "B.Mask" "B.Paste")
			(net "FPGA_FLASH_CLK")
		)
		(zone
			(layer "B.Cu")
			(hatch none 0.5)
			(connect_pads
				(clearance 0)
			)
			(min_thickness 0.25)
			(keepout
				(tracks allowed)
				(vias not_allowed)
				(pads allowed)
				(copperpour not_allowed)
				(footprints allowed)
			)
			(placement
				(enabled no)
				(sheetname "")
			)
			(fill
				(thermal_gap 0.5)
				(thermal_bridge_width 0.5)
				(island_removal_mode 0)
			)
			(polygon
				(pts
					(xy 110.1852 -62.0522) (xy 110.1852 -61.8998) (xy 110.7948 -61.8998) (xy 110.7948 -62.0522)
				)
			)
		)
	)
	(footprint ""
		(layer "B.Cu")
		(at 77.089 -49.403 180)
		(property "Reference" "C64"
			(at -3.048 -0.03937 0)
			(unlocked yes)
			(layer "B.SilkS")
			(effects
				(font
					(size 0.7874 0.5842)
					(thickness 0.1524)
				)
				(justify mirror)
			)
		)
		(property "Value" "VAL*"
			(at -0.0762 3.134106 180)
			(unlocked yes)
			(layer "B.Fab")
			(hide yes)
			(effects
				(font
					(size 0.7874 0.5842)
					(thickness 0.1524)
				)
				(justify mirror)
			)
		)
		(property "Tolerance" "TOL*"
			(at -0.0762 4.048506 180)
			(unlocked yes)
			(layer "Cmts.User")
			(hide yes)
			(effects
				(font
					(size 0.7874 0.5842)
					(thickness 0.1524)
				)
				(justify mirror)
			)
		)
		(property "User Part Number" "PARTNUM*"
			(at -0.1016 5.013706 180)
			(unlocked yes)
			(layer "Cmts.User")
			(hide yes)
			(effects
				(font
					(size 0.7874 0.5842)
					(thickness 0.1524)
				)
				(justify mirror)
			)
		)
		(property "Device Type" "CAPACITOR-G107-0F106-EM,10UF,2A"
			(at -0.0508 2.194306 180)
			(unlocked yes)
			(layer "B.Fab")
			(hide yes)
			(effects
				(font
					(size 0.7874 0.5842)
					(thickness 0.1524)
				)
				(justify mirror)
			)
		)
		(duplicate_pad_numbers_are_jumpers no)
		(fp_line
			(start 1.5748 0.9398)
			(end -1.5748 0.9398)
			(stroke
				(width 0.1)
				(type default)
			)
			(layer "B.SilkS")
		)
		(fp_line
			(start 1.5748 -0.9398)
			(end 1.5748 0.9398)
			(stroke
				(width 0.1)
				(type default)
			)
			(layer "B.SilkS")
		)
		(fp_line
			(start -1.5748 0.9398)
			(end -1.5748 -0.9398)
			(stroke
				(width 0.1)
				(type default)
			)
			(layer "B.SilkS")
		)
		(fp_line
			(start -1.5748 -0.9398)
			(end 1.5748 -0.9398)
			(stroke
				(width 0.1)
				(type default)
			)
			(layer "B.SilkS")
		)
		(fp_rect
			(start 1.5748 0.9398)
			(end -1.5748 -0.9398)
			(stroke
				(width 0)
				(type default)
			)
			(fill no)
			(layer "B.CrtYd")
		)
		(fp_line
			(start 1.016 0.635)
			(end -1.016 0.635)
			(stroke
				(width 0.1)
				(type default)
			)
			(layer "B.Fab")
		)
		(fp_line
			(start 1.016 -0.635)
			(end 1.016 0.635)
			(stroke
				(width 0.1)
				(type default)
			)
			(layer "B.Fab")
		)
		(fp_line
			(start -1.016 0.635)
			(end -1.016 -0.635)
			(stroke
				(width 0.1)
				(type default)
			)
			(layer "B.Fab")
		)
		(fp_line
			(start -1.016 -0.635)
			(end 1.016 -0.635)
			(stroke
				(width 0.1)
				(type default)
			)
			(layer "B.Fab")
		)
		(pad "1" smd rect
			(at 0.8382 0)
			(size 0.9652 1.3716)
			(layers "B.Cu" "B.Mask" "B.Paste")
			(net "XP5R0V_MAC_USB")
		)
		(pad "2" smd rect
			(at -0.8382 0)
			(size 0.9652 1.3716)
			(layers "B.Cu" "B.Mask" "B.Paste")
			(net "SG")
		)
		(zone
			(layer "B.Cu")
			(hatch none 0.5)
			(connect_pads
				(clearance 0)
			)
			(min_thickness 0.25)
			(keepout
				(tracks allowed)
				(vias not_allowed)
				(pads allowed)
				(copperpour not_allowed)
				(footprints allowed)
			)
			(placement
				(enabled no)
				(sheetname "")
			)
			(fill
				(thermal_gap 0.5)
				(thermal_bridge_width 0.5)
				(island_removal_mode 0)
			)
			(polygon
				(pts
					(xy 76.8604 -50.038) (xy 76.8604 -48.768) (xy 77.3176 -48.768) (xy 77.3176 -50.038)
				)
			)
		)
	)
)
